(kicad_pcb
	(version 20260206)
	(generator "pcbnew")
	(generator_version "10.0")
	(general
		(thickness 1.6)
		(legacy_teardrops no)
	)
	(paper "A4")
	(title_block
		(title "03242023_DA0F0TMBIJ0_F0T_Motherboard_J_brd_V01_OCP.brd")
		(comment 1 "Grand Teton / footprint 3586 of 6105 (J23), pads 113-224 of 291")
	)
	(layers
		(0 "F.Cu" signal "TOP")
		(4 "In1.Cu" signal "GND")
		(6 "In2.Cu" signal "IN1")
		(8 "In3.Cu" signal "GND1")
		(10 "In4.Cu" signal "IN2")
		(12 "In5.Cu" signal "GND2")
		(14 "In6.Cu" signal "IN3")
		(16 "In7.Cu" signal "GND3")
		(18 "In8.Cu" signal "VCC")
		(20 "In9.Cu" signal "VCC1")
		(22 "In10.Cu" signal "GND4")
		(24 "In11.Cu" signal "IN4")
		(26 "In12.Cu" signal "GND5")
		(28 "In13.Cu" signal "IN5")
		(30 "In14.Cu" signal "GND6")
		(32 "In15.Cu" signal "IN6")
		(34 "In16.Cu" signal "GND7")
		(2 "B.Cu" signal "BOTTOM")
		(9 "F.Adhes" user "F.Adhesive")
		(11 "B.Adhes" user "B.Adhesive")
		(13 "F.Paste" user "Package Geometry/Pastemask Top")
		(15 "B.Paste" user "Package Geometry/Pastemask Bottom")
		(5 "F.SilkS" user "Ref Des/Silkscreen Top")
		(7 "B.SilkS" user "Ref Des/Silkscreen Bottom")
		(1 "F.Mask" user "Board Geometry/Soldermask Top")
		(3 "B.Mask" user "Board Geometry/Soldermask Bottom")
		(17 "Dwgs.User" user "User.Drawings")
		(19 "Cmts.User" user "User.Comments")
		(21 "Eco1.User" user "User.Eco1")
		(23 "Eco2.User" user "User.Eco2")
		(25 "Edge.Cuts" user "Board Geometry/Outline")
		(27 "Margin" user)
		(31 "F.CrtYd" user "Package Geometry/Place Bound Top")
		(29 "B.CrtYd" user "Package Geometry/Place Bound Bottom")
		(35 "F.Fab" user "Ref Des/Assembly Top")
		(33 "B.Fab" user "Ref Des/Assembly Bottom")
	)
	(footprint ""
		(layer "F.Cu")
		(at 10.19048 -258.091686)
		(property "Reference" "J23"
			(at -5.69468 -80.480408 0)
			(unlocked yes)
			(layer "F.SilkS")
			(effects
				(font
					(size 0.7874 0.5842)
					(thickness 0.1524)
				)
				(justify left)
			)
		)
		(property "Value" ""
			(at 0 0 0)
			(layer "F.Fab")
			(effects
				(font
					(size 1.27 1.27)
				)
			)
		)
		(duplicate_pad_numbers_are_jumpers no)
		(pad "113" smd rect
			(at -2.050034 36.975034 270)
			(size 0.519938 1.4986)
			(layers "F.Cu" "F.Mask" "F.Paste")
			(net "M_D_CPU1_SB_DQ<9>")
		)
		(pad "114" smd rect
			(at -2.050034 37.824918 270)
			(size 0.519938 1.4986)
			(layers "F.Cu" "F.Mask" "F.Paste")
			(net "GND")
		)
		(pad "115" smd rect
			(at -2.050034 38.675056 270)
			(size 0.519938 1.4986)
			(layers "F.Cu" "F.Mask" "F.Paste")
			(net "M_D_CPU1_SB_DQS_DP<1>")
		)
		(pad "116" smd rect
			(at -2.050034 39.52494 270)
			(size 0.519938 1.4986)
			(layers "F.Cu" "F.Mask" "F.Paste")
			(net "M_D_CPU1_SB_DQS_DN<1>")
		)
		(pad "117" smd rect
			(at -2.050034 40.375078 270)
			(size 0.519938 1.4986)
			(layers "F.Cu" "F.Mask" "F.Paste")
			(net "GND")
		)
		(pad "118" smd rect
			(at -2.050034 41.224962 270)
			(size 0.519938 1.4986)
			(layers "F.Cu" "F.Mask" "F.Paste")
			(net "M_D_CPU1_SB_DQ<12>")
		)
		(pad "119" smd rect
			(at -2.050034 42.0751 270)
			(size 0.519938 1.4986)
			(layers "F.Cu" "F.Mask" "F.Paste")
			(net "GND")
		)
		(pad "120" smd rect
			(at -2.050034 42.924984 270)
			(size 0.519938 1.4986)
			(layers "F.Cu" "F.Mask" "F.Paste")
			(net "M_D_CPU1_SB_DQ<13>")
		)
		(pad "121" smd rect
			(at -2.050034 43.775122 270)
			(size 0.519938 1.4986)
			(layers "F.Cu" "F.Mask" "F.Paste")
			(net "GND")
		)
		(pad "122" smd rect
			(at -2.050034 44.625006 270)
			(size 0.519938 1.4986)
			(layers "F.Cu" "F.Mask" "F.Paste")
			(net "M_D_CPU1_SB_DQ<16>")
		)
		(pad "123" smd rect
			(at -2.050034 45.47489 270)
			(size 0.519938 1.4986)
			(layers "F.Cu" "F.Mask" "F.Paste")
			(net "GND")
		)
		(pad "124" smd rect
			(at -2.050034 46.325028 270)
			(size 0.519938 1.4986)
			(layers "F.Cu" "F.Mask" "F.Paste")
			(net "M_D_CPU1_SB_DQ<17>")
		)
		(pad "125" smd rect
			(at -2.050034 47.174912 270)
			(size 0.519938 1.4986)
			(layers "F.Cu" "F.Mask" "F.Paste")
			(net "GND")
		)
		(pad "126" smd rect
			(at -2.050034 48.02505 270)
			(size 0.519938 1.4986)
			(layers "F.Cu" "F.Mask" "F.Paste")
			(net "M_D_CPU1_SB_DQS_DP<2>")
		)
		(pad "127" smd rect
			(at -2.050034 48.874934 270)
			(size 0.519938 1.4986)
			(layers "F.Cu" "F.Mask" "F.Paste")
			(net "M_D_CPU1_SB_DQS_DN<2>")
		)
		(pad "128" smd rect
			(at -2.050034 49.725072 270)
			(size 0.519938 1.4986)
			(layers "F.Cu" "F.Mask" "F.Paste")
			(net "GND")
		)
		(pad "129" smd rect
			(at -2.050034 50.574956 270)
			(size 0.519938 1.4986)
			(layers "F.Cu" "F.Mask" "F.Paste")
			(net "M_D_CPU1_SB_DQ<20>")
		)
		(pad "130" smd rect
			(at -2.050034 51.425094 270)
			(size 0.519938 1.4986)
			(layers "F.Cu" "F.Mask" "F.Paste")
			(net "GND")
		)
		(pad "131" smd rect
			(at -2.050034 52.274978 270)
			(size 0.519938 1.4986)
			(layers "F.Cu" "F.Mask" "F.Paste")
			(net "M_D_CPU1_SB_DQ<21>")
		)
		(pad "132" smd rect
			(at -2.050034 53.125116 270)
			(size 0.519938 1.4986)
			(layers "F.Cu" "F.Mask" "F.Paste")
			(net "GND")
		)
		(pad "133" smd rect
			(at -2.050034 53.975 270)
			(size 0.519938 1.4986)
			(layers "F.Cu" "F.Mask" "F.Paste")
			(net "M_D_CPU1_SB_DQ<24>")
		)
		(pad "134" smd rect
			(at -2.050034 54.824884 270)
			(size 0.519938 1.4986)
			(layers "F.Cu" "F.Mask" "F.Paste")
			(net "GND")
		)
		(pad "135" smd rect
			(at -2.050034 55.675022 270)
			(size 0.519938 1.4986)
			(layers "F.Cu" "F.Mask" "F.Paste")
			(net "M_D_CPU1_SB_DQ<25>")
		)
		(pad "136" smd rect
			(at -2.050034 56.524906 270)
			(size 0.519938 1.4986)
			(layers "F.Cu" "F.Mask" "F.Paste")
			(net "GND")
		)
		(pad "137" smd rect
			(at -2.050034 57.375044 270)
			(size 0.519938 1.4986)
			(layers "F.Cu" "F.Mask" "F.Paste")
			(net "M_D_CPU1_SB_DQS_DP<3>")
		)
		(pad "138" smd rect
			(at -2.050034 58.224928 270)
			(size 0.519938 1.4986)
			(layers "F.Cu" "F.Mask" "F.Paste")
			(net "M_D_CPU1_SB_DQS_DN<3>")
		)
		(pad "139" smd rect
			(at -2.050034 59.075066 270)
			(size 0.519938 1.4986)
			(layers "F.Cu" "F.Mask" "F.Paste")
			(net "GND")
		)
		(pad "140" smd rect
			(at -2.050034 59.92495 270)
			(size 0.519938 1.4986)
			(layers "F.Cu" "F.Mask" "F.Paste")
			(net "M_D_CPU1_SB_DQ<28>")
		)
		(pad "141" smd rect
			(at -2.050034 60.775088 270)
			(size 0.519938 1.4986)
			(layers "F.Cu" "F.Mask" "F.Paste")
			(net "GND")
		)
		(pad "142" smd rect
			(at -2.050034 61.624972 270)
			(size 0.519938 1.4986)
			(layers "F.Cu" "F.Mask" "F.Paste")
			(net "M_D_CPU1_SB_DQ<29>")
		)
		(pad "143" smd rect
			(at -2.050034 62.47511 270)
			(size 0.519938 1.4986)
			(layers "F.Cu" "F.Mask" "F.Paste")
			(net "GND")
		)
		(pad "144" smd rect
			(at -2.050034 63.324994 270)
			(size 0.519938 1.4986)
			(layers "F.Cu" "F.Mask" "F.Paste")
			(net "TP_CHD_CPU1_DIMM1_FRU_1")
		)
		(pad "145" smd rect
			(at 2.050034 -63.324994 270)
			(size 0.519938 1.4986)
			(layers "F.Cu" "F.Mask" "F.Paste")
			(net "P12V_S3_AUX_CPU1_NVDIMM")
		)
		(pad "146" smd rect
			(at 2.050034 -62.47511 270)
			(size 0.519938 1.4986)
			(layers "F.Cu" "F.Mask" "F.Paste")
			(net "P12V_S3_AUX_CPU1_NVDIMM")
		)
		(pad "147" smd rect
			(at 2.050034 -61.624972 270)
			(size 0.519938 1.4986)
			(layers "F.Cu" "F.Mask" "F.Paste")
			(net "PWRGD_CHD_CPU1_DIMM1")
		)
		(pad "148" smd rect
			(at 2.050034 -60.775088 270)
			(size 0.519938 1.4986)
			(layers "F.Cu" "F.Mask" "F.Paste")
			(net "PD_CHD_CPU1_DIMM1_SAA")
		)
		(pad "149" smd rect
			(at 2.050034 -59.92495 270)
			(size 0.519938 1.4986)
			(layers "F.Cu" "F.Mask" "F.Paste")
			(net "TP_CHD_CPU1_DIMM1_FRU_2")
		)
		(pad "150" smd rect
			(at 2.050034 -59.075066 270)
			(size 0.519938 1.4986)
			(layers "F.Cu" "F.Mask" "F.Paste")
			(net "TP_CHD_CPU1_DIMM1_FRU_3")
		)
		(pad "151" smd rect
			(at 2.050034 -58.224928 270)
			(size 0.519938 1.4986)
			(layers "F.Cu" "F.Mask" "F.Paste")
			(net "GND")
		)
		(pad "152" smd rect
			(at 2.050034 -57.375044 270)
			(size 0.519938 1.4986)
			(layers "F.Cu" "F.Mask" "F.Paste")
			(net "M_D_CPU1_SA_DQ<2>")
		)
		(pad "153" smd rect
			(at 2.050034 -56.524906 270)
			(size 0.519938 1.4986)
			(layers "F.Cu" "F.Mask" "F.Paste")
			(net "GND")
		)
		(pad "154" smd rect
			(at 2.050034 -55.675022 270)
			(size 0.519938 1.4986)
			(layers "F.Cu" "F.Mask" "F.Paste")
			(net "M_D_CPU1_SA_DQ<3>")
		)
		(pad "155" smd rect
			(at 2.050034 -54.824884 270)
			(size 0.519938 1.4986)
			(layers "F.Cu" "F.Mask" "F.Paste")
			(net "GND")
		)
		(pad "156" smd rect
			(at 2.050034 -53.975 270)
			(size 0.519938 1.4986)
			(layers "F.Cu" "F.Mask" "F.Paste")
			(net "M_D_CPU1_SA_DQS_DN<5>")
		)
		(pad "157" smd rect
			(at 2.050034 -53.125116 270)
			(size 0.519938 1.4986)
			(layers "F.Cu" "F.Mask" "F.Paste")
			(net "M_D_CPU1_SA_DQS_DP<5>")
		)
		(pad "158" smd rect
			(at 2.050034 -52.274978 270)
			(size 0.519938 1.4986)
			(layers "F.Cu" "F.Mask" "F.Paste")
			(net "GND")
		)
		(pad "159" smd rect
			(at 2.050034 -51.425094 270)
			(size 0.519938 1.4986)
			(layers "F.Cu" "F.Mask" "F.Paste")
			(net "M_D_CPU1_SA_DQ<6>")
		)
		(pad "160" smd rect
			(at 2.050034 -50.574956 270)
			(size 0.519938 1.4986)
			(layers "F.Cu" "F.Mask" "F.Paste")
			(net "GND")
		)
		(pad "161" smd rect
			(at 2.050034 -49.725072 270)
			(size 0.519938 1.4986)
			(layers "F.Cu" "F.Mask" "F.Paste")
			(net "M_D_CPU1_SA_DQ<7>")
		)
		(pad "162" smd rect
			(at 2.050034 -48.874934 270)
			(size 0.519938 1.4986)
			(layers "F.Cu" "F.Mask" "F.Paste")
			(net "GND")
		)
		(pad "163" smd rect
			(at 2.050034 -48.02505 270)
			(size 0.519938 1.4986)
			(layers "F.Cu" "F.Mask" "F.Paste")
			(net "M_D_CPU1_SA_DQ<10>")
		)
		(pad "164" smd rect
			(at 2.050034 -47.174912 270)
			(size 0.519938 1.4986)
			(layers "F.Cu" "F.Mask" "F.Paste")
			(net "GND")
		)
		(pad "165" smd rect
			(at 2.050034 -46.325028 270)
			(size 0.519938 1.4986)
			(layers "F.Cu" "F.Mask" "F.Paste")
			(net "M_D_CPU1_SA_DQ<11>")
		)
		(pad "166" smd rect
			(at 2.050034 -45.47489 270)
			(size 0.519938 1.4986)
			(layers "F.Cu" "F.Mask" "F.Paste")
			(net "GND")
		)
		(pad "167" smd rect
			(at 2.050034 -44.625006 270)
			(size 0.519938 1.4986)
			(layers "F.Cu" "F.Mask" "F.Paste")
			(net "M_D_CPU1_SA_DQS_DN<6>")
		)
		(pad "168" smd rect
			(at 2.050034 -43.775122 270)
			(size 0.519938 1.4986)
			(layers "F.Cu" "F.Mask" "F.Paste")
			(net "M_D_CPU1_SA_DQS_DP<6>")
		)
		(pad "169" smd rect
			(at 2.050034 -42.924984 270)
			(size 0.519938 1.4986)
			(layers "F.Cu" "F.Mask" "F.Paste")
			(net "GND")
		)
		(pad "170" smd rect
			(at 2.050034 -42.0751 270)
			(size 0.519938 1.4986)
			(layers "F.Cu" "F.Mask" "F.Paste")
			(net "M_D_CPU1_SA_DQ<14>")
		)
		(pad "171" smd rect
			(at 2.050034 -41.224962 270)
			(size 0.519938 1.4986)
			(layers "F.Cu" "F.Mask" "F.Paste")
			(net "GND")
		)
		(pad "172" smd rect
			(at 2.050034 -40.375078 270)
			(size 0.519938 1.4986)
			(layers "F.Cu" "F.Mask" "F.Paste")
			(net "M_D_CPU1_SA_DQ<15>")
		)
		(pad "173" smd rect
			(at 2.050034 -39.52494 270)
			(size 0.519938 1.4986)
			(layers "F.Cu" "F.Mask" "F.Paste")
			(net "GND")
		)
		(pad "174" smd rect
			(at 2.050034 -38.675056 270)
			(size 0.519938 1.4986)
			(layers "F.Cu" "F.Mask" "F.Paste")
			(net "M_D_CPU1_SA_DQ<18>")
		)
		(pad "175" smd rect
			(at 2.050034 -37.824918 270)
			(size 0.519938 1.4986)
			(layers "F.Cu" "F.Mask" "F.Paste")
			(net "GND")
		)
		(pad "176" smd rect
			(at 2.050034 -36.975034 270)
			(size 0.519938 1.4986)
			(layers "F.Cu" "F.Mask" "F.Paste")
			(net "M_D_CPU1_SA_DQ<19>")
		)
		(pad "177" smd rect
			(at 2.050034 -36.124896 270)
			(size 0.519938 1.4986)
			(layers "F.Cu" "F.Mask" "F.Paste")
			(net "GND")
		)
		(pad "178" smd rect
			(at 2.050034 -35.275012 270)
			(size 0.519938 1.4986)
			(layers "F.Cu" "F.Mask" "F.Paste")
			(net "M_D_CPU1_SA_DQS_DN<7>")
		)
		(pad "179" smd rect
			(at 2.050034 -34.425128 270)
			(size 0.519938 1.4986)
			(layers "F.Cu" "F.Mask" "F.Paste")
			(net "M_D_CPU1_SA_DQS_DP<7>")
		)
		(pad "180" smd rect
			(at 2.050034 -33.57499 270)
			(size 0.519938 1.4986)
			(layers "F.Cu" "F.Mask" "F.Paste")
			(net "GND")
		)
		(pad "181" smd rect
			(at 2.050034 -32.725106 270)
			(size 0.519938 1.4986)
			(layers "F.Cu" "F.Mask" "F.Paste")
			(net "M_D_CPU1_SA_DQ<22>")
		)
		(pad "182" smd rect
			(at 2.050034 -31.874968 270)
			(size 0.519938 1.4986)
			(layers "F.Cu" "F.Mask" "F.Paste")
			(net "GND")
		)
		(pad "183" smd rect
			(at 2.050034 -31.025084 270)
			(size 0.519938 1.4986)
			(layers "F.Cu" "F.Mask" "F.Paste")
			(net "M_D_CPU1_SA_DQ<23>")
		)
		(pad "184" smd rect
			(at 2.050034 -30.174946 270)
			(size 0.519938 1.4986)
			(layers "F.Cu" "F.Mask" "F.Paste")
			(net "GND")
		)
		(pad "185" smd rect
			(at 2.050034 -29.325062 270)
			(size 0.519938 1.4986)
			(layers "F.Cu" "F.Mask" "F.Paste")
			(net "M_D_CPU1_SA_DQ<26>")
		)
		(pad "186" smd rect
			(at 2.050034 -28.474924 270)
			(size 0.519938 1.4986)
			(layers "F.Cu" "F.Mask" "F.Paste")
			(net "GND")
		)
		(pad "187" smd rect
			(at 2.050034 -27.62504 270)
			(size 0.519938 1.4986)
			(layers "F.Cu" "F.Mask" "F.Paste")
			(net "M_D_CPU1_SA_DQ<27>")
		)
		(pad "188" smd rect
			(at 2.050034 -26.774902 270)
			(size 0.519938 1.4986)
			(layers "F.Cu" "F.Mask" "F.Paste")
			(net "GND")
		)
		(pad "189" smd rect
			(at 2.050034 -25.925018 270)
			(size 0.519938 1.4986)
			(layers "F.Cu" "F.Mask" "F.Paste")
			(net "M_D_CPU1_SA_DQS_DN<8>")
		)
		(pad "190" smd rect
			(at 2.050034 -25.07488 270)
			(size 0.519938 1.4986)
			(layers "F.Cu" "F.Mask" "F.Paste")
			(net "M_D_CPU1_SA_DQS_DP<8>")
		)
		(pad "191" smd rect
			(at 2.050034 -24.224996 270)
			(size 0.519938 1.4986)
			(layers "F.Cu" "F.Mask" "F.Paste")
			(net "GND")
		)
		(pad "192" smd rect
			(at 2.050034 -23.375112 270)
			(size 0.519938 1.4986)
			(layers "F.Cu" "F.Mask" "F.Paste")
			(net "M_D_CPU1_SA_DQ<30>")
		)
		(pad "193" smd rect
			(at 2.050034 -22.524974 270)
			(size 0.519938 1.4986)
			(layers "F.Cu" "F.Mask" "F.Paste")
			(net "GND")
		)
		(pad "194" smd rect
			(at 2.050034 -21.67509 270)
			(size 0.519938 1.4986)
			(layers "F.Cu" "F.Mask" "F.Paste")
			(net "M_D_CPU1_SA_DQ<31>")
		)
		(pad "195" smd rect
			(at 2.050034 -20.824952 270)
			(size 0.519938 1.4986)
			(layers "F.Cu" "F.Mask" "F.Paste")
			(net "GND")
		)
		(pad "196" smd rect
			(at 2.050034 -19.975068 270)
			(size 0.519938 1.4986)
			(layers "F.Cu" "F.Mask" "F.Paste")
			(net "M_D_CPU1_SA_CB<2>")
		)
		(pad "197" smd rect
			(at 2.050034 -19.12493 270)
			(size 0.519938 1.4986)
			(layers "F.Cu" "F.Mask" "F.Paste")
			(net "GND")
		)
		(pad "198" smd rect
			(at 2.050034 -18.275046 270)
			(size 0.519938 1.4986)
			(layers "F.Cu" "F.Mask" "F.Paste")
			(net "M_D_CPU1_SA_CB<3>")
		)
		(pad "199" smd rect
			(at 2.050034 -17.424908 270)
			(size 0.519938 1.4986)
			(layers "F.Cu" "F.Mask" "F.Paste")
			(net "GND")
		)
		(pad "200" smd rect
			(at 2.050034 -16.575024 270)
			(size 0.519938 1.4986)
			(layers "F.Cu" "F.Mask" "F.Paste")
			(net "M_D_CPU1_SA_DQS_DN<9>")
		)
		(pad "201" smd rect
			(at 2.050034 -15.724886 270)
			(size 0.519938 1.4986)
			(layers "F.Cu" "F.Mask" "F.Paste")
			(net "M_D_CPU1_SA_DQS_DP<9>")
		)
		(pad "202" smd rect
			(at 2.050034 -14.875002 270)
			(size 0.519938 1.4986)
			(layers "F.Cu" "F.Mask" "F.Paste")
			(net "GND")
		)
		(pad "203" smd rect
			(at 2.050034 -14.025118 270)
			(size 0.519938 1.4986)
			(layers "F.Cu" "F.Mask" "F.Paste")
			(net "M_D_CPU1_SA_CB<6>")
		)
		(pad "204" smd rect
			(at 2.050034 -13.17498 270)
			(size 0.519938 1.4986)
			(layers "F.Cu" "F.Mask" "F.Paste")
			(net "GND")
		)
		(pad "205" smd rect
			(at 2.050034 -12.325096 270)
			(size 0.519938 1.4986)
			(layers "F.Cu" "F.Mask" "F.Paste")
			(net "M_D_CPU1_SA_CB<7>")
		)
		(pad "206" smd rect
			(at 2.050034 -11.474958 270)
			(size 0.519938 1.4986)
			(layers "F.Cu" "F.Mask" "F.Paste")
			(net "GND")
		)
		(pad "207" smd rect
			(at 2.050034 -10.625074 270)
			(size 0.519938 1.4986)
			(layers "F.Cu" "F.Mask" "F.Paste")
			(net "RST_M_CD_CPU1_FPGA_N")
		)
		(pad "208" smd rect
			(at 2.050034 -9.774936 270)
			(size 0.519938 1.4986)
			(layers "F.Cu" "F.Mask" "F.Paste")
			(net "GND")
		)
		(pad "209" smd rect
			(at 2.050034 -8.925052 270)
			(size 0.519938 1.4986)
			(layers "F.Cu" "F.Mask" "F.Paste")
			(net "M_D_CPU1_SA_CS_N<1>")
		)
		(pad "210" smd rect
			(at 2.050034 -8.074914 270)
			(size 0.519938 1.4986)
			(layers "F.Cu" "F.Mask" "F.Paste")
			(net "GND")
		)
		(pad "211" smd rect
			(at 2.050034 -7.22503 270)
			(size 0.519938 1.4986)
			(layers "F.Cu" "F.Mask" "F.Paste")
			(net "M_D_CPU1_SA_CA<1>")
		)
		(pad "212" smd rect
			(at 2.050034 -6.374892 270)
			(size 0.519938 1.4986)
			(layers "F.Cu" "F.Mask" "F.Paste")
			(net "GND")
		)
		(pad "213" smd rect
			(at 2.050034 -5.525008 270)
			(size 0.519938 1.4986)
			(layers "F.Cu" "F.Mask" "F.Paste")
			(net "M_D_CPU1_SA_CA<3>")
		)
		(pad "214" smd rect
			(at 2.050034 -4.675124 270)
			(size 0.519938 1.4986)
			(layers "F.Cu" "F.Mask" "F.Paste")
			(net "GND")
		)
		(pad "215" smd rect
			(at 2.050034 -3.824986 270)
			(size 0.519938 1.4986)
			(layers "F.Cu" "F.Mask" "F.Paste")
			(net "M_D_CPU1_SA_CA<5>")
		)
		(pad "216" smd rect
			(at 2.050034 -2.975102 270)
			(size 0.519938 1.4986)
			(layers "F.Cu" "F.Mask" "F.Paste")
			(net "GND")
		)
		(pad "217" smd rect
			(at 2.050034 -2.124964 270)
			(size 0.519938 1.4986)
			(layers "F.Cu" "F.Mask" "F.Paste")
			(net "M_D_CPU1_CLK_DP<0>")
		)
		(pad "218" smd rect
			(at 2.050034 -1.27508 270)
			(size 0.519938 1.4986)
			(layers "F.Cu" "F.Mask" "F.Paste")
			(net "M_D_CPU1_CLK_DN<0>")
		)
		(pad "219" smd rect
			(at 2.050034 -0.424942 270)
			(size 0.519938 1.4986)
			(layers "F.Cu" "F.Mask" "F.Paste")
			(net "GND")
		)
		(pad "220" smd rect
			(at 2.050034 5.525008 270)
			(size 0.519938 1.4986)
			(layers "F.Cu" "F.Mask" "F.Paste")
			(net "TP_CHD_CPU1_DIMM1_FRU_4")
		)
		(pad "221" smd rect
			(at 2.050034 6.374892 270)
			(size 0.519938 1.4986)
			(layers "F.Cu" "F.Mask" "F.Paste")
			(net "M_D_CPU1_SB_CA<1>")
		)
		(pad "222" smd rect
			(at 2.050034 7.22503 270)
			(size 0.519938 1.4986)
			(layers "F.Cu" "F.Mask" "F.Paste")
			(net "GND")
		)
		(pad "223" smd rect
			(at 2.050034 8.074914 270)
			(size 0.519938 1.4986)
			(layers "F.Cu" "F.Mask" "F.Paste")
			(net "M_D_CPU1_SB_CA<3>")
		)
		(pad "224" smd rect
			(at 2.050034 8.925052 270)
			(size 0.519938 1.4986)
			(layers "F.Cu" "F.Mask" "F.Paste")
			(net "GND")
		)
	)
)
